(kicad_pcb
	(version 20260206)
	(generator "pcbnew")
	(generator_version "10.0")
	(general
		(thickness 1.6)
		(legacy_teardrops no)
	)
	(paper "A4")
	(title_block
		(title "Wiwynn_Tioga_Pass_MB.brd")
		(comment 1 "Tioga Pass / footprints 2853-2859 of 4770")
	)
	(layers
		(0 "F.Cu" signal "TOP")
		(4 "In1.Cu" signal "L2GND")
		(6 "In2.Cu" signal "L3")
		(8 "In3.Cu" signal "L4GND")
		(10 "In4.Cu" signal "L5")
		(12 "In5.Cu" signal "L6GND")
		(14 "In6.Cu" signal "L7VCC")
		(16 "In7.Cu" signal "L8VCC")
		(18 "In8.Cu" signal "L9GND")
		(20 "In9.Cu" signal "L10")
		(22 "In10.Cu" signal "L11GND")
		(24 "In11.Cu" signal "L12")
		(26 "In12.Cu" signal "L13GND")
		(2 "B.Cu" signal "BOTTOM")
		(9 "F.Adhes" user "F.Adhesive")
		(11 "B.Adhes" user "B.Adhesive")
		(13 "F.Paste" user "Package Geometry/Pastemask Top")
		(15 "B.Paste" user "Package Geometry/Pastemask Bottom")
		(5 "F.SilkS" user "Ref Des/Silkscreen Top")
		(7 "B.SilkS" user "Ref Des/Silkscreen Bottom")
		(1 "F.Mask" user "Board Geometry/Soldermask Top")
		(3 "B.Mask" user "Board Geometry/Soldermask Bottom")
		(17 "Dwgs.User" user "User.Drawings")
		(19 "Cmts.User" user "User.Comments")
		(21 "Eco1.User" user "User.Eco1")
		(23 "Eco2.User" user "User.Eco2")
		(25 "Edge.Cuts" user "Board Geometry/Outline")
		(27 "Margin" user)
		(31 "F.CrtYd" user "Package Geometry/Place Bound Top")
		(29 "B.CrtYd" user "Package Geometry/Place Bound Bottom")
		(35 "F.Fab" user "Ref Des/Assembly Top")
		(33 "B.Fab" user "Ref Des/Assembly Bottom")
	)
	(footprint ""
		(layer "B.Cu")
		(at 401.55114 -76.66736 -90)
		(property "Reference" "U6W2"
			(at 0 0 90)
			(layer "B.SilkS")
			(hide yes)
			(effects
				(font
					(size 1.27 1.27)
				)
				(justify mirror)
			)
		)
		(property "Value" "*"
			(at 0.1143 -9.3091 270)
			(unlocked yes)
			(layer "B.Fab")
			(hide yes)
			(effects
				(font
					(size 1.27 1.016)
					(thickness 0.1524)
				)
				(justify mirror)
			)
		)
		(property "Device Type" "TCA9517DGKR-GP_DISCRET-G8-TCA9A"
			(at 0.1143 -10.9093 270)
			(unlocked yes)
			(layer "B.Fab")
			(hide yes)
			(effects
				(font
					(size 1.27 1.016)
					(thickness 0.1524)
				)
				(justify mirror)
			)
		)
		(duplicate_pad_numbers_are_jumpers no)
		(fp_line
			(start 1.778 1.0922)
			(end 1.778 3.048)
			(stroke
				(width 0.508)
				(type default)
			)
			(layer "B.SilkS")
		)
		(fp_line
			(start -1.0795 1.016)
			(end -1.0795 -1.016)
			(stroke
				(width 0.1524)
				(type default)
			)
			(layer "B.SilkS")
		)
		(fp_line
			(start 1.9558 1.016)
			(end -1.0795 1.016)
			(stroke
				(width 0.1524)
				(type default)
			)
			(layer "B.SilkS")
		)
		(fp_line
			(start 1.4478 -0.0381)
			(end 1.9558 0.4699)
			(stroke
				(width 0.1524)
				(type default)
			)
			(layer "B.SilkS")
		)
		(fp_line
			(start 1.9558 -0.5461)
			(end 1.4478 -0.0381)
			(stroke
				(width 0.1524)
				(type default)
			)
			(layer "B.SilkS")
		)
		(fp_line
			(start -1.0795 -1.016)
			(end 1.9558 -1.016)
			(stroke
				(width 0.1524)
				(type default)
			)
			(layer "B.SilkS")
		)
		(fp_line
			(start 1.9558 -1.016)
			(end 1.9558 1.016)
			(stroke
				(width 0.1524)
				(type default)
			)
			(layer "B.SilkS")
		)
		(fp_poly
			(pts
				(xy 1.1557 -1.016) (xy 1.1557 1.016) (xy -1.1557 1.016) (xy -1.1557 -1.016)
			)
			(stroke
				(width 0)
				(type default)
			)
			(fill yes)
			(layer "B.SilkS")
		)
		(fp_rect
			(start 1.4986 2.4511)
			(end -1.4986 -2.4511)
			(stroke
				(width 0)
				(type default)
			)
			(fill no)
			(layer "B.CrtYd")
		)
		(fp_poly
			(pts
				(xy 2.032 3.302) (xy 2.032 -3.302) (xy -2.032 -3.302) (xy -2.032 -2.1209) (xy -1.4986 -2.1209) (xy -1.4986 -2.4511)
				(xy 1.4986 -2.4511) (xy 1.4986 2.4511) (xy -1.4986 2.4511) (xy -1.4986 -2.1082) (xy -2.032 -2.1082)
				(xy -2.032 3.302)
			)
			(stroke
				(width 0)
				(type default)
			)
			(fill no)
			(layer "B.CrtYd")
		)
		(fp_rect
			(start 2.032 3.302)
			(end -2.032 -3.302)
			(stroke
				(width 0)
				(type default)
			)
			(fill no)
			(layer "B.Fab")
		)
		(pad "1" smd rect
			(at 0.97536 2.05486 90)
			(size 0.3556 1.524)
			(layers "B.Cu" "B.Mask" "B.Paste")
			(net "P3V3_STBY")
		)
		(pad "2" smd rect
			(at 0.32512 2.05486 90)
			(size 0.3556 1.524)
			(layers "B.Cu" "B.Mask" "B.Paste")
			(net "SMB_PMBUS_BMC_STBY_LVC3_SCL_R1")
		)
		(pad "3" smd rect
			(at -0.32512 2.05486 90)
			(size 0.3556 1.524)
			(layers "B.Cu" "B.Mask" "B.Paste")
			(net "SMB_PMBUS_BMC_STBY_LVC3_SDA_R1")
		)
		(pad "4" smd rect
			(at -0.97536 2.05486 90)
			(size 0.3556 1.524)
			(layers "B.Cu" "B.Mask" "B.Paste")
			(net "GND")
		)
		(pad "5" smd rect
			(at -0.97536 -2.05486 90)
			(size 0.3556 1.524)
			(layers "B.Cu" "B.Mask" "B.Paste")
			(net "HSC_SMBUS_SWITCH_EN")
		)
		(pad "6" smd rect
			(at -0.32512 -2.05486 90)
			(size 0.3556 1.524)
			(layers "B.Cu" "B.Mask" "B.Paste")
			(net "SMB_BMC_PMBUS_STBY_LVC3_SDA")
		)
		(pad "7" smd rect
			(at 0.32512 -2.05486 90)
			(size 0.3556 1.524)
			(layers "B.Cu" "B.Mask" "B.Paste")
			(net "SMB_BMC_PMBUS_STBY_LVC3_SCL")
		)
		(pad "8" smd rect
			(at 0.97536 -2.05486 90)
			(size 0.3556 1.524)
			(layers "B.Cu" "B.Mask" "B.Paste")
			(net "P3V3_STBY")
		)
	)
	(footprint ""
		(layer "B.Cu")
		(at 367.637314 -35.364166 180)
		(property "Reference" "R8F12"
			(at 0 0 0)
			(layer "B.SilkS")
			(hide yes)
			(effects
				(font
					(size 1.27 1.27)
				)
				(justify mirror)
			)
		)
		(property "Value" ""
			(at 0 0 0)
			(layer "B.Fab")
			(effects
				(font
					(size 1.27 1.27)
				)
				(justify mirror)
			)
		)
		(duplicate_pad_numbers_are_jumpers no)
		(fp_poly
			(pts
				(xy 0.2794 -0.1016) (xy -0.2794 -0.1016) (xy -0.2794 0.9906) (xy 0.2794 0.9906)
			)
			(stroke
				(width 0)
				(type default)
			)
			(fill no)
			(layer "B.CrtYd")
		)
		(fp_line
			(start 0.2794 0.9906)
			(end -0.2794 0.9906)
			(stroke
				(width 0.1)
				(type default)
			)
			(layer "B.Fab")
		)
		(fp_line
			(start 0.2794 -0.1016)
			(end 0.2794 0.9906)
			(stroke
				(width 0.1)
				(type default)
			)
			(layer "B.Fab")
		)
		(fp_line
			(start -0.2794 0.9906)
			(end -0.2794 -0.1016)
			(stroke
				(width 0.1)
				(type default)
			)
			(layer "B.Fab")
		)
		(fp_line
			(start -0.2794 -0.1016)
			(end 0.2794 -0.1016)
			(stroke
				(width 0.1)
				(type default)
			)
			(layer "B.Fab")
		)
		(pad "1" smd rect
			(at 0 0)
			(size 0.508 0.508)
			(layers "B.Cu" "B.Mask" "B.Paste")
			(net "SPI_BMC_BT_DI")
		)
		(pad "2" smd rect
			(at 0 0.889)
			(size 0.508 0.508)
			(layers "B.Cu" "B.Mask" "B.Paste")
			(net "SPI_BMC_BT_DI_R")
		)
		(zone
			(layer "B.Cu")
			(hatch none 0.5)
			(connect_pads
				(clearance 0)
			)
			(min_thickness 0.25)
			(keepout
				(tracks not_allowed)
				(vias allowed)
				(pads allowed)
				(copperpour not_allowed)
				(footprints allowed)
			)
			(placement
				(enabled no)
				(sheetname "")
			)
			(fill
				(thermal_gap 0.5)
				(thermal_bridge_width 0.5)
				(island_removal_mode 0)
			)
			(polygon
				(pts
					(xy 367.383314 -35.999166) (xy 367.891314 -35.999166) (xy 367.891314 -35.618166) (xy 367.383314 -35.618166)
				)
			)
		)
		(zone
			(layer "B.Cu")
			(hatch none 0.5)
			(connect_pads
				(clearance 0)
			)
			(min_thickness 0.25)
			(keepout
				(tracks allowed)
				(vias not_allowed)
				(pads allowed)
				(copperpour not_allowed)
				(footprints allowed)
			)
			(placement
				(enabled no)
				(sheetname "")
			)
			(fill
				(thermal_gap 0.5)
				(thermal_bridge_width 0.5)
				(island_removal_mode 0)
			)
			(polygon
				(pts
					(xy 367.383314 -35.618166) (xy 367.891314 -35.618166) (xy 367.891314 -35.999166) (xy 367.383314 -35.999166)
				)
			)
		)
	)
	(footprint ""
		(layer "B.Cu")
		(at 390.635744 -25.794716 -90)
		(property "Reference" "C2T15"
			(at 0 0 90)
			(layer "B.SilkS")
			(hide yes)
			(effects
				(font
					(size 1.27 1.27)
				)
				(justify mirror)
			)
		)
		(property "Value" ""
			(at 0 0 90)
			(layer "B.Fab")
			(effects
				(font
					(size 1.27 1.27)
				)
				(justify mirror)
			)
		)
		(duplicate_pad_numbers_are_jumpers no)
		(fp_poly
			(pts
				(xy -0.3048 -0.1016) (xy -0.3048 0.9906) (xy 0.3048 0.9906) (xy 0.3048 -0.1016)
			)
			(stroke
				(width 0)
				(type default)
			)
			(fill no)
			(layer "B.CrtYd")
		)
		(fp_line
			(start -0.3048 0.9906)
			(end -0.3048 -0.1016)
			(stroke
				(width 0.1)
				(type default)
			)
			(layer "B.Fab")
		)
		(fp_line
			(start 0.3048 0.9906)
			(end -0.3048 0.9906)
			(stroke
				(width 0.1)
				(type default)
			)
			(layer "B.Fab")
		)
		(fp_line
			(start -0.3048 -0.1016)
			(end 0.3048 -0.1016)
			(stroke
				(width 0.1)
				(type default)
			)
			(layer "B.Fab")
		)
		(fp_line
			(start 0.3048 -0.1016)
			(end 0.3048 0.9906)
			(stroke
				(width 0.1)
				(type default)
			)
			(layer "B.Fab")
		)
		(pad "1" smd rect
			(at 0 0 90)
			(size 0.508 0.508)
			(layers "B.Cu" "B.Mask" "B.Paste")
			(net "P3V3")
		)
		(pad "2" smd rect
			(at 0 0.889 90)
			(size 0.508 0.508)
			(layers "B.Cu" "B.Mask" "B.Paste")
			(net "GND")
		)
		(zone
			(layer "B.Cu")
			(hatch none 0.5)
			(connect_pads
				(clearance 0)
			)
			(min_thickness 0.25)
			(keepout
				(tracks not_allowed)
				(vias allowed)
				(pads allowed)
				(copperpour not_allowed)
				(footprints allowed)
			)
			(placement
				(enabled no)
				(sheetname "")
			)
			(fill
				(thermal_gap 0.5)
				(thermal_bridge_width 0.5)
				(island_removal_mode 0)
			)
			(polygon
				(pts
					(xy 390.000744 -25.540716) (xy 390.000744 -26.048716) (xy 390.381744 -26.048716) (xy 390.381744 -25.540716)
				)
			)
		)
		(zone
			(layer "B.Cu")
			(hatch none 0.5)
			(connect_pads
				(clearance 0)
			)
			(min_thickness 0.25)
			(keepout
				(tracks allowed)
				(vias not_allowed)
				(pads allowed)
				(copperpour not_allowed)
				(footprints allowed)
			)
			(placement
				(enabled no)
				(sheetname "")
			)
			(fill
				(thermal_gap 0.5)
				(thermal_bridge_width 0.5)
				(island_removal_mode 0)
			)
			(polygon
				(pts
					(xy 390.381744 -25.540716) (xy 390.381744 -26.048716) (xy 390.000744 -26.048716) (xy 390.000744 -25.540716)
				)
			)
		)
	)
	(footprint ""
		(layer "B.Cu")
		(at 156.06522 -124.0917)
		(property "Reference" "R7M3"
			(at 0 0 0)
			(layer "B.SilkS")
			(hide yes)
			(effects
				(font
					(size 1.27 1.27)
				)
				(justify mirror)
			)
		)
		(property "Value" ""
			(at 0 0 0)
			(layer "B.Fab")
			(effects
				(font
					(size 1.27 1.27)
				)
				(justify mirror)
			)
		)
		(duplicate_pad_numbers_are_jumpers no)
		(fp_poly
			(pts
				(xy 0.2794 -0.1016) (xy -0.2794 -0.1016) (xy -0.2794 0.9906) (xy 0.2794 0.9906)
			)
			(stroke
				(width 0)
				(type default)
			)
			(fill no)
			(layer "B.CrtYd")
		)
		(fp_line
			(start -0.2794 -0.1016)
			(end 0.2794 -0.1016)
			(stroke
				(width 0.1)
				(type default)
			)
			(layer "B.Fab")
		)
		(fp_line
			(start -0.2794 0.9906)
			(end -0.2794 -0.1016)
			(stroke
				(width 0.1)
				(type default)
			)
			(layer "B.Fab")
		)
		(fp_line
			(start 0.2794 -0.1016)
			(end 0.2794 0.9906)
			(stroke
				(width 0.1)
				(type default)
			)
			(layer "B.Fab")
		)
		(fp_line
			(start 0.2794 0.9906)
			(end -0.2794 0.9906)
			(stroke
				(width 0.1)
				(type default)
			)
			(layer "B.Fab")
		)
		(pad "1" smd rect
			(at 0 0 180)
			(size 0.508 0.508)
			(layers "B.Cu" "B.Mask" "B.Paste")
			(net "SMB_DDR_KLM_SCL_G_R")
		)
		(pad "2" smd rect
			(at 0 0.889 180)
			(size 0.508 0.508)
			(layers "B.Cu" "B.Mask" "B.Paste")
			(net "SMB_DDR_KLM_SCL_G")
		)
		(zone
			(layer "B.Cu")
			(hatch none 0.5)
			(connect_pads
				(clearance 0)
			)
			(min_thickness 0.25)
			(keepout
				(tracks allowed)
				(vias not_allowed)
				(pads allowed)
				(copperpour not_allowed)
				(footprints allowed)
			)
			(placement
				(enabled no)
				(sheetname "")
			)
			(fill
				(thermal_gap 0.5)
				(thermal_bridge_width 0.5)
				(island_removal_mode 0)
			)
			(polygon
				(pts
					(xy 156.31922 -123.8377) (xy 155.81122 -123.8377) (xy 155.81122 -123.4567) (xy 156.31922 -123.4567)
				)
			)
		)
		(zone
			(layer "B.Cu")
			(hatch none 0.5)
			(connect_pads
				(clearance 0)
			)
			(min_thickness 0.25)
			(keepout
				(tracks not_allowed)
				(vias allowed)
				(pads allowed)
				(copperpour not_allowed)
				(footprints allowed)
			)
			(placement
				(enabled no)
				(sheetname "")
			)
			(fill
				(thermal_gap 0.5)
				(thermal_bridge_width 0.5)
				(island_removal_mode 0)
			)
			(polygon
				(pts
					(xy 156.31922 -123.4567) (xy 155.81122 -123.4567) (xy 155.81122 -123.8377) (xy 156.31922 -123.8377)
				)
			)
		)
	)
	(footprint ""
		(layer "B.Cu")
		(at 252.1585 -3.3528 -90)
		(property "Reference" "C5G52"
			(at -1.14681 0.76708 0)
			(unlocked yes)
			(layer "B.SilkS")
			(effects
				(font
					(size 0.7874 0.5842)
					(thickness 0.1524)
				)
				(justify mirror)
			)
		)
		(property "Value" ""
			(at 0 0 90)
			(layer "B.Fab")
			(effects
				(font
					(size 1.27 1.27)
				)
				(justify mirror)
			)
		)
		(duplicate_pad_numbers_are_jumpers no)
		(fp_rect
			(start 0.4953 1.6002)
			(end -0.4953 -0.2032)
			(stroke
				(width 0)
				(type default)
			)
			(fill no)
			(layer "B.CrtYd")
		)
		(fp_line
			(start -0.4953 1.6002)
			(end 0.4953 1.6002)
			(stroke
				(width 0.1)
				(type default)
			)
			(layer "B.Fab")
		)
		(fp_line
			(start 0.4953 1.6002)
			(end 0.4953 -0.2032)
			(stroke
				(width 0.1)
				(type default)
			)
			(layer "B.Fab")
		)
		(fp_line
			(start -0.4953 -0.2032)
			(end -0.4953 1.6002)
			(stroke
				(width 0.1)
				(type default)
			)
			(layer "B.Fab")
		)
		(fp_line
			(start 0.4953 -0.2032)
			(end -0.4953 -0.2032)
			(stroke
				(width 0.1)
				(type default)
			)
			(layer "B.Fab")
		)
		(pad "1" smd rect
			(at 0 0 90)
			(size 0.762 0.889)
			(layers "B.Cu" "B.Mask" "B.Paste")
			(net "PVDDQ_ABC")
		)
		(pad "2" smd rect
			(at 0 1.397 90)
			(size 0.762 0.889)
			(layers "B.Cu" "B.Mask" "B.Paste")
			(net "GND")
		)
		(zone
			(layer "B.Cu")
			(hatch none 0.5)
			(connect_pads
				(clearance 0)
			)
			(min_thickness 0.25)
			(keepout
				(tracks not_allowed)
				(vias allowed)
				(pads allowed)
				(copperpour not_allowed)
				(footprints allowed)
			)
			(placement
				(enabled no)
				(sheetname "")
			)
			(fill
				(thermal_gap 0.5)
				(thermal_bridge_width 0.5)
				(island_removal_mode 0)
			)
			(polygon
				(pts
					(xy 251.206 -2.9718) (xy 251.714 -2.9718) (xy 251.714 -3.7338) (xy 251.206 -3.7338)
				)
			)
		)
	)
	(footprint ""
		(layer "B.Cu")
		(at 401.992846 -27.124152)
		(property "Reference" "C9G17"
			(at 0 0 0)
			(layer "B.SilkS")
			(hide yes)
			(effects
				(font
					(size 1.27 1.27)
				)
				(justify mirror)
			)
		)
		(property "Value" ""
			(at 0 0 0)
			(layer "B.Fab")
			(effects
				(font
					(size 1.27 1.27)
				)
				(justify mirror)
			)
		)
		(duplicate_pad_numbers_are_jumpers no)
		(fp_poly
			(pts
				(xy -0.3048 -0.1016) (xy -0.3048 0.9906) (xy 0.3048 0.9906) (xy 0.3048 -0.1016)
			)
			(stroke
				(width 0)
				(type default)
			)
			(fill no)
			(layer "B.CrtYd")
		)
		(fp_line
			(start -0.3048 -0.1016)
			(end 0.3048 -0.1016)
			(stroke
				(width 0.1)
				(type default)
			)
			(layer "B.Fab")
		)
		(fp_line
			(start -0.3048 0.9906)
			(end -0.3048 -0.1016)
			(stroke
				(width 0.1)
				(type default)
			)
			(layer "B.Fab")
		)
		(fp_line
			(start 0.3048 -0.1016)
			(end 0.3048 0.9906)
			(stroke
				(width 0.1)
				(type default)
			)
			(layer "B.Fab")
		)
		(fp_line
			(start 0.3048 0.9906)
			(end -0.3048 0.9906)
			(stroke
				(width 0.1)
				(type default)
			)
			(layer "B.Fab")
		)
		(pad "1" smd rect
			(at 0 0 180)
			(size 0.508 0.508)
			(layers "B.Cu" "B.Mask" "B.Paste")
			(net "A_P12V_STBY_SCALED")
		)
		(pad "2" smd rect
			(at 0 0.889 180)
			(size 0.508 0.508)
			(layers "B.Cu" "B.Mask" "B.Paste")
			(net "GND")
		)
		(zone
			(layer "B.Cu")
			(hatch none 0.5)
			(connect_pads
				(clearance 0)
			)
			(min_thickness 0.25)
			(keepout
				(tracks allowed)
				(vias not_allowed)
				(pads allowed)
				(copperpour not_allowed)
				(footprints allowed)
			)
			(placement
				(enabled no)
				(sheetname "")
			)
			(fill
				(thermal_gap 0.5)
				(thermal_bridge_width 0.5)
				(island_removal_mode 0)
			)
			(polygon
				(pts
					(xy 402.246846 -26.870152) (xy 401.738846 -26.870152) (xy 401.738846 -26.489152) (xy 402.246846 -26.489152)
				)
			)
		)
		(zone
			(layer "B.Cu")
			(hatch none 0.5)
			(connect_pads
				(clearance 0)
			)
			(min_thickness 0.25)
			(keepout
				(tracks not_allowed)
				(vias allowed)
				(pads allowed)
				(copperpour not_allowed)
				(footprints allowed)
			)
			(placement
				(enabled no)
				(sheetname "")
			)
			(fill
				(thermal_gap 0.5)
				(thermal_bridge_width 0.5)
				(island_removal_mode 0)
			)
			(polygon
				(pts
					(xy 402.246846 -26.489152) (xy 401.738846 -26.489152) (xy 401.738846 -26.870152) (xy 402.246846 -26.870152)
				)
			)
		)
	)
	(footprint ""
		(layer "B.Cu")
		(at 401.25777 -127.659384 90)
		(property "Reference" "C2M23"
			(at 0 0 90)
			(layer "B.SilkS")
			(hide yes)
			(effects
				(font
					(size 1.27 1.27)
				)
				(justify mirror)
			)
		)
		(property "Value" ""
			(at 0 0 90)
			(layer "B.Fab")
			(effects
				(font
					(size 1.27 1.27)
				)
				(justify mirror)
			)
		)
		(duplicate_pad_numbers_are_jumpers no)
		(fp_poly
			(pts
				(xy -0.3048 -0.1016) (xy -0.3048 0.9906) (xy 0.3048 0.9906) (xy 0.3048 -0.1016)
			)
			(stroke
				(width 0)
				(type default)
			)
			(fill no)
			(layer "B.CrtYd")
		)
		(fp_line
			(start 0.3048 -0.1016)
			(end 0.3048 0.9906)
			(stroke
				(width 0.1)
				(type default)
			)
			(layer "B.Fab")
		)
		(fp_line
			(start -0.3048 -0.1016)
			(end 0.3048 -0.1016)
			(stroke
				(width 0.1)
				(type default)
			)
			(layer "B.Fab")
		)
		(fp_line
			(start 0.3048 0.9906)
			(end -0.3048 0.9906)
			(stroke
				(width 0.1)
				(type default)
			)
			(layer "B.Fab")
		)
		(fp_line
			(start -0.3048 0.9906)
			(end -0.3048 -0.1016)
			(stroke
				(width 0.1)
				(type default)
			)
			(layer "B.Fab")
		)
		(pad "1" smd rect
			(at 0 0 270)
			(size 0.508 0.508)
			(layers "B.Cu" "B.Mask" "B.Paste")
			(net "PE_PCH_SPRV_TX_DP")
		)
		(pad "2" smd rect
			(at 0 0.889 270)
			(size 0.508 0.508)
			(layers "B.Cu" "B.Mask" "B.Paste")
			(net "PE_PCH_SPRV_TX_C_DP")
		)
		(zone
			(layer "B.Cu")
			(hatch none 0.5)
			(connect_pads
				(clearance 0)
			)
			(min_thickness 0.25)
			(keepout
				(tracks allowed)
				(vias not_allowed)
				(pads allowed)
				(copperpour not_allowed)
				(footprints allowed)
			)
			(placement
				(enabled no)
				(sheetname "")
			)
			(fill
				(thermal_gap 0.5)
				(thermal_bridge_width 0.5)
				(island_removal_mode 0)
			)
			(polygon
				(pts
					(xy 401.51177 -127.913384) (xy 401.51177 -127.405384) (xy 401.89277 -127.405384) (xy 401.89277 -127.913384)
				)
			)
		)
		(zone
			(layer "B.Cu")
			(hatch none 0.5)
			(connect_pads
				(clearance 0)
			)
			(min_thickness 0.25)
			(keepout
				(tracks not_allowed)
				(vias allowed)
				(pads allowed)
				(copperpour not_allowed)
				(footprints allowed)
			)
			(placement
				(enabled no)
				(sheetname "")
			)
			(fill
				(thermal_gap 0.5)
				(thermal_bridge_width 0.5)
				(island_removal_mode 0)
			)
			(polygon
				(pts
					(xy 401.89277 -127.913384) (xy 401.89277 -127.405384) (xy 401.51177 -127.405384) (xy 401.51177 -127.913384)
				)
			)
		)
	)
)
